# T6G (Grand Teton) — schematic netlist excerpt (pin names and nets, part order shuffled) for the footprints in the layout excerpt that follows; sources: Cadence DE-HDL packaged netlist, KiCad conversion of 04192023_DAF0TMB3IC0_F0TG_MB_C_brd_V02_OCP.brd

C1770  Q_CAP  0.1UF 25V 10% X7R  pkg 0402  page 130 : A = P3V3_AUX ; B = GND
R6291  Q_RES  0 5% CHIP  pkg 0402LF  page 179 : A = USB_HUB2_TI_GANGED_MRP_I2C_SLV_CFG0 ; B = USB_HUB2_MRP_I2C_SLV_CFG0

(kicad_pcb
	(version 20260206)
	(generator "pcbnew")
	(generator_version "10.0")
	(general
		(thickness 1.6)
		(legacy_teardrops no)
	)
	(paper "A4")
	(title_block
		(title "04192023_DAF0TMB3IC0_F0TG_MB_C_brd_V02_OCP.brd")
		(comment 1 "Grand Teton / footprints 2000-2001 of 8354")
	)
	(layers
		(0 "F.Cu" signal "TOP")
		(4 "In1.Cu" signal "GND")
		(6 "In2.Cu" signal "IN1")
		(8 "In3.Cu" signal "GND1")
		(10 "In4.Cu" signal "IN2")
		(12 "In5.Cu" signal "GND2")
		(14 "In6.Cu" signal "IN3")
		(16 "In7.Cu" signal "GND3")
		(18 "In8.Cu" signal "VCC")
		(20 "In9.Cu" signal "VCC1")
		(22 "In10.Cu" signal "GND4")
		(24 "In11.Cu" signal "IN4")
		(26 "In12.Cu" signal "GND5")
		(28 "In13.Cu" signal "IN5")
		(30 "In14.Cu" signal "GND6")
		(32 "In15.Cu" signal "IN6")
		(34 "In16.Cu" signal "GND7")
		(2 "B.Cu" signal "BOTTOM")
		(9 "F.Adhes" user "F.Adhesive")
		(11 "B.Adhes" user "B.Adhesive")
		(13 "F.Paste" user "Package Geometry/Pastemask Top")
		(15 "B.Paste" user "Package Geometry/Pastemask Bottom")
		(5 "F.SilkS" user "Ref Des/Silkscreen Top")
		(7 "B.SilkS" user "Ref Des/Silkscreen Bottom")
		(1 "F.Mask" user "Board Geometry/Soldermask Top")
		(3 "B.Mask" user "Board Geometry/Soldermask Bottom")
		(17 "Dwgs.User" user "User.Drawings")
		(19 "Cmts.User" user "User.Comments")
		(21 "Eco1.User" user "User.Eco1")
		(23 "Eco2.User" user "User.Eco2")
		(25 "Edge.Cuts" user "Board Geometry/Outline")
		(27 "Margin" user)
		(31 "F.CrtYd" user "Package Geometry/Place Bound Top")
		(29 "B.CrtYd" user "Package Geometry/Place Bound Bottom")
		(35 "F.Fab" user "Ref Des/Assembly Top")
		(33 "B.Fab" user "Ref Des/Assembly Bottom")
	)
	(footprint ""
		(layer "F.Cu")
		(at 49.276 -435.991 -90)
		(property "Reference" "C1770"
			(at 0 0 270)
			(layer "F.SilkS")
			(hide yes)
			(effects
				(font
					(size 1.27 1.27)
				)
			)
		)
		(property "Value" ""
			(at 0 0 270)
			(layer "F.Fab")
			(effects
				(font
					(size 1.27 1.27)
				)
			)
		)
		(duplicate_pad_numbers_are_jumpers no)
		(fp_line
			(start -0.7874 0.4064)
			(end -0.7874 -0.4064)
			(stroke
				(width 0.1524)
				(type default)
			)
			(layer "F.SilkS")
		)
		(fp_line
			(start 0.7874 0.4064)
			(end -0.7874 0.4064)
			(stroke
				(width 0.1524)
				(type default)
			)
			(layer "F.SilkS")
		)
		(fp_line
			(start -0.7874 -0.4064)
			(end 0.7874 -0.4064)
			(stroke
				(width 0.1524)
				(type default)
			)
			(layer "F.SilkS")
		)
		(fp_line
			(start 0.7874 -0.4064)
			(end 0.7874 0.4064)
			(stroke
				(width 0.1524)
				(type default)
			)
			(layer "F.SilkS")
		)
		(fp_line
			(start -0.67945 0.3048)
			(end -0.67945 -0.305054)
			(stroke
				(width 0.1)
				(type default)
			)
			(layer "F.Fab")
		)
		(fp_line
			(start -0.12065 0.3048)
			(end -0.67945 0.3048)
			(stroke
				(width 0.1)
				(type default)
			)
			(layer "F.Fab")
		)
		(fp_line
			(start 0.120396 0.3048)
			(end 0.120396 0.2794)
			(stroke
				(width 0.1)
				(type default)
			)
			(layer "F.Fab")
		)
		(fp_line
			(start 0.67945 0.3048)
			(end 0.120396 0.3048)
			(stroke
				(width 0.1)
				(type default)
			)
			(layer "F.Fab")
		)
		(fp_line
			(start -0.12065 0.2794)
			(end -0.12065 0.3048)
			(stroke
				(width 0.1)
				(type default)
			)
			(layer "F.Fab")
		)
		(fp_line
			(start 0.120396 0.2794)
			(end -0.12065 0.2794)
			(stroke
				(width 0.1)
				(type default)
			)
			(layer "F.Fab")
		)
		(fp_line
			(start -0.12065 -0.2794)
			(end 0.12065 -0.2794)
			(stroke
				(width 0.1)
				(type default)
			)
			(layer "F.Fab")
		)
		(fp_line
			(start 0.12065 -0.2794)
			(end 0.12065 -0.3048)
			(stroke
				(width 0.1)
				(type default)
			)
			(layer "F.Fab")
		)
		(fp_line
			(start 0.12065 -0.3048)
			(end 0.67945 -0.3048)
			(stroke
				(width 0.1)
				(type default)
			)
			(layer "F.Fab")
		)
		(fp_line
			(start 0.67945 -0.3048)
			(end 0.67945 0.3048)
			(stroke
				(width 0.1)
				(type default)
			)
			(layer "F.Fab")
		)
		(fp_line
			(start -0.67945 -0.305054)
			(end -0.12065 -0.305054)
			(stroke
				(width 0.1)
				(type default)
			)
			(layer "F.Fab")
		)
		(fp_line
			(start -0.12065 -0.305054)
			(end -0.12065 -0.2794)
			(stroke
				(width 0.1)
				(type default)
			)
			(layer "F.Fab")
		)
		(pad "1" smd circle
			(at -0.40005 0 270)
			(size 0 0)
			(layers "F.Cu" "F.Mask" "F.Paste")
			(net "P3V3_AUX")
		)
		(pad "2" smd circle
			(at 0.40005 0 270)
			(size 0 0)
			(layers "F.Cu" "F.Mask" "F.Paste")
			(net "GND")
		)
	)
	(footprint ""
		(layer "F.Cu")
		(at 111.251238 -39.40175 90)
		(property "Reference" "R6291"
			(at 0 0 90)
			(layer "F.SilkS")
			(hide yes)
			(effects
				(font
					(size 1.27 1.27)
				)
			)
		)
		(property "Value" ""
			(at 0 0 90)
			(layer "F.Fab")
			(effects
				(font
					(size 1.27 1.27)
				)
			)
		)
		(duplicate_pad_numbers_are_jumpers no)
		(fp_line
			(start 0.7874 -0.4064)
			(end 0.7874 0.4064)
			(stroke
				(width 0.1524)
				(type default)
			)
			(layer "F.SilkS")
		)
		(fp_line
			(start -0.7874 -0.4064)
			(end 0.7874 -0.4064)
			(stroke
				(width 0.1524)
				(type default)
			)
			(layer "F.SilkS")
		)
		(fp_line
			(start 0.7874 0.4064)
			(end -0.7874 0.4064)
			(stroke
				(width 0.1524)
				(type default)
			)
			(layer "F.SilkS")
		)
		(fp_line
			(start -0.7874 0.4064)
			(end -0.7874 -0.4064)
			(stroke
				(width 0.1524)
				(type default)
			)
			(layer "F.SilkS")
		)
		(fp_line
			(start -0.12065 -0.305054)
			(end -0.12065 -0.2794)
			(stroke
				(width 0.1)
				(type default)
			)
			(layer "F.Fab")
		)
		(fp_line
			(start -0.67945 -0.305054)
			(end -0.12065 -0.305054)
			(stroke
				(width 0.1)
				(type default)
			)
			(layer "F.Fab")
		)
		(fp_line
			(start 0.67945 -0.3048)
			(end 0.67945 0.3048)
			(stroke
				(width 0.1)
				(type default)
			)
			(layer "F.Fab")
		)
		(fp_line
			(start 0.12065 -0.3048)
			(end 0.67945 -0.3048)
			(stroke
				(width 0.1)
				(type default)
			)
			(layer "F.Fab")
		)
		(fp_line
			(start 0.12065 -0.2794)
			(end 0.12065 -0.3048)
			(stroke
				(width 0.1)
				(type default)
			)
			(layer "F.Fab")
		)
		(fp_line
			(start -0.12065 -0.2794)
			(end 0.12065 -0.2794)
			(stroke
				(width 0.1)
				(type default)
			)
			(layer "F.Fab")
		)
		(fp_line
			(start 0.120396 0.2794)
			(end -0.12065 0.2794)
			(stroke
				(width 0.1)
				(type default)
			)
			(layer "F.Fab")
		)
		(fp_line
			(start -0.12065 0.2794)
			(end -0.12065 0.3048)
			(stroke
				(width 0.1)
				(type default)
			)
			(layer "F.Fab")
		)
		(fp_line
			(start 0.67945 0.3048)
			(end 0.120396 0.3048)
			(stroke
				(width 0.1)
				(type default)
			)
			(layer "F.Fab")
		)
		(fp_line
			(start 0.120396 0.3048)
			(end 0.120396 0.2794)
			(stroke
				(width 0.1)
				(type default)
			)
			(layer "F.Fab")
		)
		(fp_line
			(start -0.12065 0.3048)
			(end -0.67945 0.3048)
			(stroke
				(width 0.1)
				(type default)
			)
			(layer "F.Fab")
		)
		(fp_line
			(start -0.67945 0.3048)
			(end -0.67945 -0.305054)
			(stroke
				(width 0.1)
				(type default)
			)
			(layer "F.Fab")
		)
		(pad "1" smd circle
			(at -0.40005 0 90)
			(size 0 0)
			(layers "F.Cu" "F.Mask" "F.Paste")
			(net "USB_HUB2_TI_GANGED_MRP_I2C_SLV_CFG0")
		)
		(pad "2" smd circle
			(at 0.40005 0 90)
			(size 0 0)
			(layers "F.Cu" "F.Mask" "F.Paste")
			(net "USB_HUB2_MRP_I2C_SLV_CFG0")
		)
	)
)
